# T6G (Grand Teton) — schematic netlist excerpt (pin names and nets, part order shuffled) for the footprints in the layout excerpt that follows; sources: Cadence DE-HDL packaged netlist, KiCad conversion of 04192023_DAF0TMB3IC0_F0TG_MB_C_brd_V02_OCP.brd

C6061  Q_CAP  0.01UF 50V 10% X7R  pkg C0402  page 177 : A = P1V2_AUX ; B = GND
R8045  Q_RES  1K 1% EMPTY  pkg 0402LF  page 200 : A = PVDD18_S5_P0 ; B = SVID_PVDDCR_CPU1_P0_SVD_R

(kicad_pcb
	(version 20260206)
	(generator "pcbnew")
	(generator_version "10.0")
	(general
		(thickness 1.6)
		(legacy_teardrops no)
	)
	(paper "A4")
	(title_block
		(title "04192023_DAF0TMB3IC0_F0TG_MB_C_brd_V02_OCP.brd")
		(comment 1 "Grand Teton / footprints 6938-6939 of 8354")
	)
	(layers
		(0 "F.Cu" signal "TOP")
		(4 "In1.Cu" signal "GND")
		(6 "In2.Cu" signal "IN1")
		(8 "In3.Cu" signal "GND1")
		(10 "In4.Cu" signal "IN2")
		(12 "In5.Cu" signal "GND2")
		(14 "In6.Cu" signal "IN3")
		(16 "In7.Cu" signal "GND3")
		(18 "In8.Cu" signal "VCC")
		(20 "In9.Cu" signal "VCC1")
		(22 "In10.Cu" signal "GND4")
		(24 "In11.Cu" signal "IN4")
		(26 "In12.Cu" signal "GND5")
		(28 "In13.Cu" signal "IN5")
		(30 "In14.Cu" signal "GND6")
		(32 "In15.Cu" signal "IN6")
		(34 "In16.Cu" signal "GND7")
		(2 "B.Cu" signal "BOTTOM")
		(9 "F.Adhes" user "F.Adhesive")
		(11 "B.Adhes" user "B.Adhesive")
		(13 "F.Paste" user "Package Geometry/Pastemask Top")
		(15 "B.Paste" user "Package Geometry/Pastemask Bottom")
		(5 "F.SilkS" user "Ref Des/Silkscreen Top")
		(7 "B.SilkS" user "Ref Des/Silkscreen Bottom")
		(1 "F.Mask" user "Board Geometry/Soldermask Top")
		(3 "B.Mask" user "Board Geometry/Soldermask Bottom")
		(17 "Dwgs.User" user "User.Drawings")
		(19 "Cmts.User" user "User.Comments")
		(21 "Eco1.User" user "User.Eco1")
		(23 "Eco2.User" user "User.Eco2")
		(25 "Edge.Cuts" user "Board Geometry/Outline")
		(27 "Margin" user)
		(31 "F.CrtYd" user "Package Geometry/Place Bound Top")
		(29 "B.CrtYd" user "Package Geometry/Place Bound Bottom")
		(35 "F.Fab" user "Ref Des/Assembly Top")
		(33 "B.Fab" user "Ref Des/Assembly Bottom")
	)
	(footprint ""
		(layer "B.Cu")
		(at 125.895608 -38.87343 90)
		(property "Reference" "C6061"
			(at 0 0 90)
			(layer "B.SilkS")
			(hide yes)
			(effects
				(font
					(size 1.27 1.27)
				)
				(justify mirror)
			)
		)
		(property "Value" ""
			(at 0 0 90)
			(layer "B.Fab")
			(effects
				(font
					(size 1.27 1.27)
				)
				(justify mirror)
			)
		)
		(duplicate_pad_numbers_are_jumpers no)
		(fp_line
			(start 0.7874 -0.4064)
			(end -0.7874 -0.4064)
			(stroke
				(width 0.1524)
				(type default)
			)
			(layer "B.SilkS")
		)
		(fp_line
			(start -0.7874 -0.4064)
			(end -0.7874 0.4064)
			(stroke
				(width 0.1524)
				(type default)
			)
			(layer "B.SilkS")
		)
		(fp_line
			(start 0.7874 0.4064)
			(end 0.7874 -0.4064)
			(stroke
				(width 0.1524)
				(type default)
			)
			(layer "B.SilkS")
		)
		(fp_line
			(start -0.7874 0.4064)
			(end 0.7874 0.4064)
			(stroke
				(width 0.1524)
				(type default)
			)
			(layer "B.SilkS")
		)
		(fp_line
			(start 0.67945 -0.305054)
			(end 0.12065 -0.305054)
			(stroke
				(width 0.1)
				(type default)
			)
			(layer "B.Fab")
		)
		(fp_line
			(start 0.12065 -0.305054)
			(end 0.12065 -0.2794)
			(stroke
				(width 0.1)
				(type default)
			)
			(layer "B.Fab")
		)
		(fp_line
			(start -0.12065 -0.3048)
			(end -0.67945 -0.3048)
			(stroke
				(width 0.1)
				(type default)
			)
			(layer "B.Fab")
		)
		(fp_line
			(start -0.67945 -0.3048)
			(end -0.67945 0.3048)
			(stroke
				(width 0.1)
				(type default)
			)
			(layer "B.Fab")
		)
		(fp_line
			(start 0.12065 -0.2794)
			(end -0.12065 -0.2794)
			(stroke
				(width 0.1)
				(type default)
			)
			(layer "B.Fab")
		)
		(fp_line
			(start -0.12065 -0.2794)
			(end -0.12065 -0.3048)
			(stroke
				(width 0.1)
				(type default)
			)
			(layer "B.Fab")
		)
		(fp_line
			(start 0.12065 0.2794)
			(end 0.12065 0.3048)
			(stroke
				(width 0.1)
				(type default)
			)
			(layer "B.Fab")
		)
		(fp_line
			(start -0.120396 0.2794)
			(end 0.12065 0.2794)
			(stroke
				(width 0.1)
				(type default)
			)
			(layer "B.Fab")
		)
		(fp_line
			(start 0.67945 0.3048)
			(end 0.67945 -0.305054)
			(stroke
				(width 0.1)
				(type default)
			)
			(layer "B.Fab")
		)
		(fp_line
			(start 0.12065 0.3048)
			(end 0.67945 0.3048)
			(stroke
				(width 0.1)
				(type default)
			)
			(layer "B.Fab")
		)
		(fp_line
			(start -0.120396 0.3048)
			(end -0.120396 0.2794)
			(stroke
				(width 0.1)
				(type default)
			)
			(layer "B.Fab")
		)
		(fp_line
			(start -0.67945 0.3048)
			(end -0.120396 0.3048)
			(stroke
				(width 0.1)
				(type default)
			)
			(layer "B.Fab")
		)
		(pad "1" smd circle
			(at 0.40005 0 270)
			(size 0 0)
			(layers "B.Cu" "B.Mask" "B.Paste")
			(net "P1V2_AUX")
		)
		(pad "2" smd circle
			(at -0.40005 0 270)
			(size 0 0)
			(layers "B.Cu" "B.Mask" "B.Paste")
			(net "GND")
		)
	)
	(footprint ""
		(layer "B.Cu")
		(at 302.133 -358.14 180)
		(property "Reference" "R8045"
			(at 0 0 0)
			(layer "B.SilkS")
			(hide yes)
			(effects
				(font
					(size 1.27 1.27)
				)
				(justify mirror)
			)
		)
		(property "Value" ""
			(at 0 0 0)
			(layer "B.Fab")
			(effects
				(font
					(size 1.27 1.27)
				)
				(justify mirror)
			)
		)
		(duplicate_pad_numbers_are_jumpers no)
		(fp_line
			(start 0.7874 0.4064)
			(end 0.7874 -0.4064)
			(stroke
				(width 0.1524)
				(type default)
			)
			(layer "B.SilkS")
		)
		(fp_line
			(start 0.7874 -0.4064)
			(end -0.7874 -0.4064)
			(stroke
				(width 0.1524)
				(type default)
			)
			(layer "B.SilkS")
		)
		(fp_line
			(start -0.7874 0.4064)
			(end 0.7874 0.4064)
			(stroke
				(width 0.1524)
				(type default)
			)
			(layer "B.SilkS")
		)
		(fp_line
			(start -0.7874 -0.4064)
			(end -0.7874 0.4064)
			(stroke
				(width 0.1524)
				(type default)
			)
			(layer "B.SilkS")
		)
		(fp_line
			(start 0.67945 0.3048)
			(end 0.67945 -0.305054)
			(stroke
				(width 0.1)
				(type default)
			)
			(layer "B.Fab")
		)
		(fp_line
			(start 0.67945 -0.305054)
			(end 0.12065 -0.305054)
			(stroke
				(width 0.1)
				(type default)
			)
			(layer "B.Fab")
		)
		(fp_line
			(start 0.12065 0.3048)
			(end 0.67945 0.3048)
			(stroke
				(width 0.1)
				(type default)
			)
			(layer "B.Fab")
		)
		(fp_line
			(start 0.12065 0.2794)
			(end 0.12065 0.3048)
			(stroke
				(width 0.1)
				(type default)
			)
			(layer "B.Fab")
		)
		(fp_line
			(start 0.12065 -0.2794)
			(end -0.12065 -0.2794)
			(stroke
				(width 0.1)
				(type default)
			)
			(layer "B.Fab")
		)
		(fp_line
			(start 0.12065 -0.305054)
			(end 0.12065 -0.2794)
			(stroke
				(width 0.1)
				(type default)
			)
			(layer "B.Fab")
		)
		(fp_line
			(start -0.120396 0.3048)
			(end -0.120396 0.2794)
			(stroke
				(width 0.1)
				(type default)
			)
			(layer "B.Fab")
		)
		(fp_line
			(start -0.120396 0.2794)
			(end 0.12065 0.2794)
			(stroke
				(width 0.1)
				(type default)
			)
			(layer "B.Fab")
		)
		(fp_line
			(start -0.12065 -0.2794)
			(end -0.12065 -0.3048)
			(stroke
				(width 0.1)
				(type default)
			)
			(layer "B.Fab")
		)
		(fp_line
			(start -0.12065 -0.3048)
			(end -0.67945 -0.3048)
			(stroke
				(width 0.1)
				(type default)
			)
			(layer "B.Fab")
		)
		(fp_line
			(start -0.67945 0.3048)
			(end -0.120396 0.3048)
			(stroke
				(width 0.1)
				(type default)
			)
			(layer "B.Fab")
		)
		(fp_line
			(start -0.67945 -0.3048)
			(end -0.67945 0.3048)
			(stroke
				(width 0.1)
				(type default)
			)
			(layer "B.Fab")
		)
		(pad "1" smd circle
			(at 0.40005 0)
			(size 0 0)
			(layers "B.Cu" "B.Mask" "B.Paste")
			(net "PVDD18_S5_P0")
		)
		(pad "2" smd circle
			(at -0.40005 0)
			(size 0 0)
			(layers "B.Cu" "B.Mask" "B.Paste")
			(net "SVID_PVDDCR_CPU1_P0_SVD_R")
		)
	)
)
